(kicad_pcb
	(version 20260206)
	(generator "pcbnew")
	(generator_version "10.0")
	(general
		(thickness 1.6)
		(legacy_teardrops no)
	)
	(paper "A4")
	(title_block
		(title "04192023_DAF0TMB3IC0_F0TG_MB_C_brd_V02_OCP.brd")
		(comment 1 "Grand Teton / footprints 2108-2110 of 8354")
	)
	(layers
		(0 "F.Cu" signal "TOP")
		(4 "In1.Cu" signal "GND")
		(6 "In2.Cu" signal "IN1")
		(8 "In3.Cu" signal "GND1")
		(10 "In4.Cu" signal "IN2")
		(12 "In5.Cu" signal "GND2")
		(14 "In6.Cu" signal "IN3")
		(16 "In7.Cu" signal "GND3")
		(18 "In8.Cu" signal "VCC")
		(20 "In9.Cu" signal "VCC1")
		(22 "In10.Cu" signal "GND4")
		(24 "In11.Cu" signal "IN4")
		(26 "In12.Cu" signal "GND5")
		(28 "In13.Cu" signal "IN5")
		(30 "In14.Cu" signal "GND6")
		(32 "In15.Cu" signal "IN6")
		(34 "In16.Cu" signal "GND7")
		(2 "B.Cu" signal "BOTTOM")
		(9 "F.Adhes" user "F.Adhesive")
		(11 "B.Adhes" user "B.Adhesive")
		(13 "F.Paste" user "Package Geometry/Pastemask Top")
		(15 "B.Paste" user "Package Geometry/Pastemask Bottom")
		(5 "F.SilkS" user "Ref Des/Silkscreen Top")
		(7 "B.SilkS" user "Ref Des/Silkscreen Bottom")
		(1 "F.Mask" user "Board Geometry/Soldermask Top")
		(3 "B.Mask" user "Board Geometry/Soldermask Bottom")
		(17 "Dwgs.User" user "User.Drawings")
		(19 "Cmts.User" user "User.Comments")
		(21 "Eco1.User" user "User.Eco1")
		(23 "Eco2.User" user "User.Eco2")
		(25 "Edge.Cuts" user "Board Geometry/Outline")
		(27 "Margin" user)
		(31 "F.CrtYd" user "Package Geometry/Place Bound Top")
		(29 "B.CrtYd" user "Package Geometry/Place Bound Bottom")
		(35 "F.Fab" user "Ref Des/Assembly Top")
		(33 "B.Fab" user "Ref Des/Assembly Bottom")
	)
	(footprint ""
		(layer "F.Cu")
		(at 179.846224 -147.086574 90)
		(property "Reference" "R70"
			(at 0 0 90)
			(layer "F.SilkS")
			(hide yes)
			(effects
				(font
					(size 1.27 1.27)
				)
			)
		)
		(property "Value" ""
			(at 0 0 90)
			(layer "F.Fab")
			(effects
				(font
					(size 1.27 1.27)
				)
			)
		)
		(duplicate_pad_numbers_are_jumpers no)
		(fp_line
			(start 0.7874 -0.4064)
			(end 0.7874 0.4064)
			(stroke
				(width 0.1524)
				(type default)
			)
			(layer "F.SilkS")
		)
		(fp_line
			(start -0.7874 -0.4064)
			(end 0.7874 -0.4064)
			(stroke
				(width 0.1524)
				(type default)
			)
			(layer "F.SilkS")
		)
		(fp_line
			(start 0.7874 0.4064)
			(end -0.7874 0.4064)
			(stroke
				(width 0.1524)
				(type default)
			)
			(layer "F.SilkS")
		)
		(fp_line
			(start -0.7874 0.4064)
			(end -0.7874 -0.4064)
			(stroke
				(width 0.1524)
				(type default)
			)
			(layer "F.SilkS")
		)
		(fp_line
			(start -0.12065 -0.305054)
			(end -0.12065 -0.2794)
			(stroke
				(width 0.1)
				(type default)
			)
			(layer "F.Fab")
		)
		(fp_line
			(start -0.67945 -0.305054)
			(end -0.12065 -0.305054)
			(stroke
				(width 0.1)
				(type default)
			)
			(layer "F.Fab")
		)
		(fp_line
			(start 0.67945 -0.3048)
			(end 0.67945 0.3048)
			(stroke
				(width 0.1)
				(type default)
			)
			(layer "F.Fab")
		)
		(fp_line
			(start 0.12065 -0.3048)
			(end 0.67945 -0.3048)
			(stroke
				(width 0.1)
				(type default)
			)
			(layer "F.Fab")
		)
		(fp_line
			(start 0.12065 -0.2794)
			(end 0.12065 -0.3048)
			(stroke
				(width 0.1)
				(type default)
			)
			(layer "F.Fab")
		)
		(fp_line
			(start -0.12065 -0.2794)
			(end 0.12065 -0.2794)
			(stroke
				(width 0.1)
				(type default)
			)
			(layer "F.Fab")
		)
		(fp_line
			(start 0.120396 0.2794)
			(end -0.12065 0.2794)
			(stroke
				(width 0.1)
				(type default)
			)
			(layer "F.Fab")
		)
		(fp_line
			(start -0.12065 0.2794)
			(end -0.12065 0.3048)
			(stroke
				(width 0.1)
				(type default)
			)
			(layer "F.Fab")
		)
		(fp_line
			(start 0.67945 0.3048)
			(end 0.120396 0.3048)
			(stroke
				(width 0.1)
				(type default)
			)
			(layer "F.Fab")
		)
		(fp_line
			(start 0.120396 0.3048)
			(end 0.120396 0.2794)
			(stroke
				(width 0.1)
				(type default)
			)
			(layer "F.Fab")
		)
		(fp_line
			(start -0.12065 0.3048)
			(end -0.67945 0.3048)
			(stroke
				(width 0.1)
				(type default)
			)
			(layer "F.Fab")
		)
		(fp_line
			(start -0.67945 0.3048)
			(end -0.67945 -0.305054)
			(stroke
				(width 0.1)
				(type default)
			)
			(layer "F.Fab")
		)
		(pad "1" smd circle
			(at -0.40005 0 90)
			(size 0 0)
			(layers "F.Cu" "F.Mask" "F.Paste")
			(net "SMB_CPU0_4_XLTR_R_SCL")
		)
		(pad "2" smd circle
			(at 0.40005 0 90)
			(size 0 0)
			(layers "F.Cu" "F.Mask" "F.Paste")
			(net "SMB_CPU0_4_XLTR_SCL")
		)
	)
	(footprint ""
		(layer "F.Cu")
		(at 427.7614 -36.642548)
		(property "Reference" "SW1"
			(at -2.2733 -7.534148 0)
			(unlocked yes)
			(layer "F.SilkS")
			(effects
				(font
					(size 0.7874 0.5842)
					(thickness 0.1524)
				)
				(justify left)
			)
		)
		(property "Value" ""
			(at 0 0 0)
			(layer "F.Fab")
			(effects
				(font
					(size 1.27 1.27)
				)
			)
		)
		(duplicate_pad_numbers_are_jumpers no)
		(fp_line
			(start -2.275078 -6.964934)
			(end -2.275078 6.964934)
			(stroke
				(width 0.1524)
				(type default)
			)
			(layer "F.SilkS")
		)
		(fp_line
			(start -2.275078 6.964934)
			(end 2.275078 6.964934)
			(stroke
				(width 0.1524)
				(type default)
			)
			(layer "F.SilkS")
		)
		(fp_line
			(start -1.8796 -5.8166)
			(end -1.8796 -5.3086)
			(stroke
				(width 0.1524)
				(type default)
			)
			(layer "F.SilkS")
		)
		(fp_line
			(start -1.8796 -5.3086)
			(end 1.9304 -5.3086)
			(stroke
				(width 0.1524)
				(type default)
			)
			(layer "F.SilkS")
		)
		(fp_line
			(start -1.8796 -4.5466)
			(end -1.8796 -4.0386)
			(stroke
				(width 0.1524)
				(type default)
			)
			(layer "F.SilkS")
		)
		(fp_line
			(start -1.8796 -4.0386)
			(end 1.9304 -4.0386)
			(stroke
				(width 0.1524)
				(type default)
			)
			(layer "F.SilkS")
		)
		(fp_line
			(start -1.8796 -3.2766)
			(end -1.8796 -2.7686)
			(stroke
				(width 0.1524)
				(type default)
			)
			(layer "F.SilkS")
		)
		(fp_line
			(start -1.8796 -2.7686)
			(end 1.9304 -2.7686)
			(stroke
				(width 0.1524)
				(type default)
			)
			(layer "F.SilkS")
		)
		(fp_line
			(start -1.8796 -2.0066)
			(end -1.8796 -1.4986)
			(stroke
				(width 0.1524)
				(type default)
			)
			(layer "F.SilkS")
		)
		(fp_line
			(start -1.8796 -1.4986)
			(end 1.9304 -1.4986)
			(stroke
				(width 0.1524)
				(type default)
			)
			(layer "F.SilkS")
		)
		(fp_line
			(start -1.8796 -0.7366)
			(end -1.8796 -0.2286)
			(stroke
				(width 0.1524)
				(type default)
			)
			(layer "F.SilkS")
		)
		(fp_line
			(start -1.8796 -0.2286)
			(end 1.9304 -0.2286)
			(stroke
				(width 0.1524)
				(type default)
			)
			(layer "F.SilkS")
		)
		(fp_line
			(start -1.8796 0.5334)
			(end -1.8796 1.0414)
			(stroke
				(width 0.1524)
				(type default)
			)
			(layer "F.SilkS")
		)
		(fp_line
			(start -1.8796 1.0414)
			(end 1.9304 1.0414)
			(stroke
				(width 0.1524)
				(type default)
			)
			(layer "F.SilkS")
		)
		(fp_line
			(start -1.8796 1.8034)
			(end -1.8796 2.3114)
			(stroke
				(width 0.1524)
				(type default)
			)
			(layer "F.SilkS")
		)
		(fp_line
			(start -1.8796 2.3114)
			(end 1.9304 2.3114)
			(stroke
				(width 0.1524)
				(type default)
			)
			(layer "F.SilkS")
		)
		(fp_line
			(start -1.8796 3.0734)
			(end -1.8796 3.5814)
			(stroke
				(width 0.1524)
				(type default)
			)
			(layer "F.SilkS")
		)
		(fp_line
			(start -1.8796 3.5814)
			(end 1.9304 3.5814)
			(stroke
				(width 0.1524)
				(type default)
			)
			(layer "F.SilkS")
		)
		(fp_line
			(start -1.8796 4.3434)
			(end -1.8796 4.8514)
			(stroke
				(width 0.1524)
				(type default)
			)
			(layer "F.SilkS")
		)
		(fp_line
			(start -1.8796 4.8514)
			(end 1.9304 4.8514)
			(stroke
				(width 0.1524)
				(type default)
			)
			(layer "F.SilkS")
		)
		(fp_line
			(start -1.8796 5.6134)
			(end -1.8796 6.1214)
			(stroke
				(width 0.1524)
				(type default)
			)
			(layer "F.SilkS")
		)
		(fp_line
			(start -1.8796 6.1214)
			(end 1.9304 6.1214)
			(stroke
				(width 0.1524)
				(type default)
			)
			(layer "F.SilkS")
		)
		(fp_line
			(start -1.122934 -6.964934)
			(end -2.275078 -6.964934)
			(stroke
				(width 0.1524)
				(type default)
			)
			(layer "F.SilkS")
		)
		(fp_line
			(start 0 -6.096)
			(end -1.122934 -6.964934)
			(stroke
				(width 0.1524)
				(type default)
			)
			(layer "F.SilkS")
		)
		(fp_line
			(start 0.0254 -5.8166)
			(end 0.0254 -5.3086)
			(stroke
				(width 0.1524)
				(type default)
			)
			(layer "F.SilkS")
		)
		(fp_line
			(start 0.0254 -4.5466)
			(end 0.0254 -4.0386)
			(stroke
				(width 0.1524)
				(type default)
			)
			(layer "F.SilkS")
		)
		(fp_line
			(start 0.0254 -3.2766)
			(end 0.0254 -2.7686)
			(stroke
				(width 0.1524)
				(type default)
			)
			(layer "F.SilkS")
		)
		(fp_line
			(start 0.0254 -2.0066)
			(end 0.0254 -1.4986)
			(stroke
				(width 0.1524)
				(type default)
			)
			(layer "F.SilkS")
		)
		(fp_line
			(start 0.0254 -0.7366)
			(end 0.0254 -0.2286)
			(stroke
				(width 0.1524)
				(type default)
			)
			(layer "F.SilkS")
		)
		(fp_line
			(start 0.0254 0.5334)
			(end 0.0254 1.0414)
			(stroke
				(width 0.1524)
				(type default)
			)
			(layer "F.SilkS")
		)
		(fp_line
			(start 0.0254 1.8034)
			(end 0.0254 2.3114)
			(stroke
				(width 0.1524)
				(type default)
			)
			(layer "F.SilkS")
		)
		(fp_line
			(start 0.0254 3.0734)
			(end 0.0254 3.5814)
			(stroke
				(width 0.1524)
				(type default)
			)
			(layer "F.SilkS")
		)
		(fp_line
			(start 0.0254 4.3434)
			(end 0.0254 4.8514)
			(stroke
				(width 0.1524)
				(type default)
			)
			(layer "F.SilkS")
		)
		(fp_line
			(start 0.0254 5.6134)
			(end 0.0254 6.1214)
			(stroke
				(width 0.1524)
				(type default)
			)
			(layer "F.SilkS")
		)
		(fp_line
			(start 1.122934 -6.964934)
			(end 0 -6.096)
			(stroke
				(width 0.1524)
				(type default)
			)
			(layer "F.SilkS")
		)
		(fp_line
			(start 1.9304 -5.8166)
			(end -1.8796 -5.8166)
			(stroke
				(width 0.1524)
				(type default)
			)
			(layer "F.SilkS")
		)
		(fp_line
			(start 1.9304 -5.3086)
			(end 1.9304 -5.8166)
			(stroke
				(width 0.1524)
				(type default)
			)
			(layer "F.SilkS")
		)
		(fp_line
			(start 1.9304 -4.5466)
			(end -1.8796 -4.5466)
			(stroke
				(width 0.1524)
				(type default)
			)
			(layer "F.SilkS")
		)
		(fp_line
			(start 1.9304 -4.0386)
			(end 1.9304 -4.5466)
			(stroke
				(width 0.1524)
				(type default)
			)
			(layer "F.SilkS")
		)
		(fp_line
			(start 1.9304 -3.2766)
			(end -1.8796 -3.2766)
			(stroke
				(width 0.1524)
				(type default)
			)
			(layer "F.SilkS")
		)
		(fp_line
			(start 1.9304 -2.7686)
			(end 1.9304 -3.2766)
			(stroke
				(width 0.1524)
				(type default)
			)
			(layer "F.SilkS")
		)
		(fp_line
			(start 1.9304 -2.0066)
			(end -1.8796 -2.0066)
			(stroke
				(width 0.1524)
				(type default)
			)
			(layer "F.SilkS")
		)
		(fp_line
			(start 1.9304 -1.4986)
			(end 1.9304 -2.0066)
			(stroke
				(width 0.1524)
				(type default)
			)
			(layer "F.SilkS")
		)
		(fp_line
			(start 1.9304 -0.7366)
			(end -1.8796 -0.7366)
			(stroke
				(width 0.1524)
				(type default)
			)
			(layer "F.SilkS")
		)
		(fp_line
			(start 1.9304 -0.2286)
			(end 1.9304 -0.7366)
			(stroke
				(width 0.1524)
				(type default)
			)
			(layer "F.SilkS")
		)
		(fp_line
			(start 1.9304 0.5334)
			(end -1.8796 0.5334)
			(stroke
				(width 0.1524)
				(type default)
			)
			(layer "F.SilkS")
		)
		(fp_line
			(start 1.9304 1.0414)
			(end 1.9304 0.5334)
			(stroke
				(width 0.1524)
				(type default)
			)
			(layer "F.SilkS")
		)
		(fp_line
			(start 1.9304 1.8034)
			(end -1.8796 1.8034)
			(stroke
				(width 0.1524)
				(type default)
			)
			(layer "F.SilkS")
		)
		(fp_line
			(start 1.9304 2.3114)
			(end 1.9304 1.8034)
			(stroke
				(width 0.1524)
				(type default)
			)
			(layer "F.SilkS")
		)
		(fp_line
			(start 1.9304 3.0734)
			(end -1.8796 3.0734)
			(stroke
				(width 0.1524)
				(type default)
			)
			(layer "F.SilkS")
		)
		(fp_line
			(start 1.9304 3.5814)
			(end 1.9304 3.0734)
			(stroke
				(width 0.1524)
				(type default)
			)
			(layer "F.SilkS")
		)
		(fp_line
			(start 1.9304 4.3434)
			(end -1.8796 4.3434)
			(stroke
				(width 0.1524)
				(type default)
			)
			(layer "F.SilkS")
		)
		(fp_line
			(start 1.9304 4.8514)
			(end 1.9304 4.3434)
			(stroke
				(width 0.1524)
				(type default)
			)
			(layer "F.SilkS")
		)
		(fp_line
			(start 1.9304 5.6134)
			(end -1.8796 5.6134)
			(stroke
				(width 0.1524)
				(type default)
			)
			(layer "F.SilkS")
		)
		(fp_line
			(start 1.9304 6.1214)
			(end 1.9304 5.6134)
			(stroke
				(width 0.1524)
				(type default)
			)
			(layer "F.SilkS")
		)
		(fp_line
			(start 2.275078 -6.964934)
			(end 1.122934 -6.964934)
			(stroke
				(width 0.1524)
				(type default)
			)
			(layer "F.SilkS")
		)
		(fp_line
			(start 2.275078 6.964934)
			(end 2.275078 -6.964934)
			(stroke
				(width 0.1524)
				(type default)
			)
			(layer "F.SilkS")
		)
		(fp_poly
			(pts
				(xy -6.40969 -5.228082) (xy -6.40969 -6.244082) (xy -5.39369 -5.736082)
			)
			(stroke
				(width 0)
				(type default)
			)
			(fill yes)
			(layer "F.SilkS")
		)
		(fp_line
			(start -2.275078 -6.964934)
			(end 2.275078 -6.964934)
			(stroke
				(width 0.1)
				(type default)
			)
			(layer "F.Fab")
		)
		(fp_line
			(start -2.275078 6.964934)
			(end -2.275078 -6.964934)
			(stroke
				(width 0.1)
				(type default)
			)
			(layer "F.Fab")
		)
		(fp_line
			(start 2.275078 -6.964934)
			(end 2.275078 6.964934)
			(stroke
				(width 0.1)
				(type default)
			)
			(layer "F.Fab")
		)
		(fp_line
			(start 2.275078 6.964934)
			(end -2.275078 6.964934)
			(stroke
				(width 0.1)
				(type default)
			)
			(layer "F.Fab")
		)
		(fp_poly
			(pts
				(xy -5.6134 -5.207) (xy -5.6134 -6.223) (xy -4.5974 -5.715)
			)
			(stroke
				(width 0)
				(type default)
			)
			(fill yes)
			(layer "F.Fab")
		)
		(pad "1" smd rect
			(at -3.81 -5.715 270)
			(size 0.762 1.27)
			(layers "F.Cu" "F.Mask" "F.Paste")
			(net "GND")
		)
		(pad "2" smd rect
			(at -3.81 -4.445 270)
			(size 0.762 1.27)
			(layers "F.Cu" "F.Mask" "F.Paste")
			(net "FM_FORCE_ALL_PWRON_ON")
		)
		(pad "3" smd rect
			(at -3.81 -3.175 270)
			(size 0.762 1.27)
			(layers "F.Cu" "F.Mask" "F.Paste")
			(net "GND")
		)
		(pad "4" smd rect
			(at -3.81 -1.905 270)
			(size 0.762 1.27)
			(layers "F.Cu" "F.Mask" "F.Paste")
			(net "PU_BIOS_USB_RECOVERY")
		)
		(pad "5" smd rect
			(at -3.81 -0.635 270)
			(size 0.762 1.27)
			(layers "F.Cu" "F.Mask" "F.Paste")
			(net "PU_FPGA_DEBUG_SW_SPARE")
		)
		(pad "6" smd rect
			(at -3.81 0.635 270)
			(size 0.762 1.27)
			(layers "F.Cu" "F.Mask" "F.Paste")
			(net "PD_BIOS_DEBUG_MODE")
		)
		(pad "7" smd rect
			(at -3.81 1.905 270)
			(size 0.762 1.27)
			(layers "F.Cu" "F.Mask" "F.Paste")
			(net "PRSNT_CPU0_N")
		)
		(pad "8" smd rect
			(at -3.81 3.175 270)
			(size 0.762 1.27)
			(layers "F.Cu" "F.Mask" "F.Paste")
			(net "PRSNT_CPU1_N")
		)
		(pad "9" smd rect
			(at -3.81 4.445 270)
			(size 0.762 1.27)
			(layers "F.Cu" "F.Mask" "F.Paste")
			(net "GND")
		)
		(pad "10" smd rect
			(at -3.81 5.715 270)
			(size 0.762 1.27)
			(layers "F.Cu" "F.Mask" "F.Paste")
			(net "PU_FPGA_DEBUG_LED_CTRL")
		)
		(pad "11" smd rect
			(at 3.81 -5.715 270)
			(size 0.762 1.27)
			(layers "F.Cu" "F.Mask" "F.Paste")
			(net "FM_SPD_CPU0_SWITCH_CTRL_N")
		)
		(pad "12" smd rect
			(at 3.81 -4.445 270)
			(size 0.762 1.27)
			(layers "F.Cu" "F.Mask" "F.Paste")
			(net "FM_FORCE_ALL_PWRON")
		)
		(pad "13" smd rect
			(at 3.81 -3.175 270)
			(size 0.762 1.27)
			(layers "F.Cu" "F.Mask" "F.Paste")
			(net "BMC_JTAG_SEL")
		)
		(pad "14" smd rect
			(at 3.81 -1.905 270)
			(size 0.762 1.27)
			(layers "F.Cu" "F.Mask" "F.Paste")
			(net "FM_BIOS_USB_RECOVERY")
		)
		(pad "15" smd rect
			(at 3.81 -0.635 270)
			(size 0.762 1.27)
			(layers "F.Cu" "F.Mask" "F.Paste")
			(net "FPGA_DEBUG_SW_SPARE")
		)
		(pad "16" smd rect
			(at 3.81 0.635 270)
			(size 0.762 1.27)
			(layers "F.Cu" "F.Mask" "F.Paste")
			(net "BIOS_DEBUG_MODE")
		)
		(pad "17" smd rect
			(at 3.81 1.905 270)
			(size 0.762 1.27)
			(layers "F.Cu" "F.Mask" "F.Paste")
			(net "FM_PRSNT_CPU0_N")
		)
		(pad "18" smd rect
			(at 3.81 3.175 270)
			(size 0.762 1.27)
			(layers "F.Cu" "F.Mask" "F.Paste")
			(net "FM_PRSNT_CPU1_N")
		)
		(pad "19" smd rect
			(at 3.81 4.445 270)
			(size 0.762 1.27)
			(layers "F.Cu" "F.Mask" "F.Paste")
			(net "FM_PASSWORD_CLEAR_N")
		)
		(pad "20" smd rect
			(at 3.81 5.715 270)
			(size 0.762 1.27)
			(layers "F.Cu" "F.Mask" "F.Paste")
			(net "FPGA_DEBUG_LED_CTRL")
		)
	)
	(footprint ""
		(layer "F.Cu")
		(at 251.06884 -92.719144 -90)
		(property "Reference" "R1641"
			(at 0 0 270)
			(layer "F.SilkS")
			(hide yes)
			(effects
				(font
					(size 1.27 1.27)
				)
			)
		)
		(property "Value" ""
			(at 0 0 270)
			(layer "F.Fab")
			(effects
				(font
					(size 1.27 1.27)
				)
			)
		)
		(duplicate_pad_numbers_are_jumpers no)
		(fp_line
			(start -0.7874 0.4064)
			(end -0.7874 -0.4064)
			(stroke
				(width 0.1524)
				(type default)
			)
			(layer "F.SilkS")
		)
		(fp_line
			(start 0.7874 0.4064)
			(end -0.7874 0.4064)
			(stroke
				(width 0.1524)
				(type default)
			)
			(layer "F.SilkS")
		)
		(fp_line
			(start -0.7874 -0.4064)
			(end 0.7874 -0.4064)
			(stroke
				(width 0.1524)
				(type default)
			)
			(layer "F.SilkS")
		)
		(fp_line
			(start 0.7874 -0.4064)
			(end 0.7874 0.4064)
			(stroke
				(width 0.1524)
				(type default)
			)
			(layer "F.SilkS")
		)
		(fp_line
			(start -0.67945 0.3048)
			(end -0.67945 -0.305054)
			(stroke
				(width 0.1)
				(type default)
			)
			(layer "F.Fab")
		)
		(fp_line
			(start -0.12065 0.3048)
			(end -0.67945 0.3048)
			(stroke
				(width 0.1)
				(type default)
			)
			(layer "F.Fab")
		)
		(fp_line
			(start 0.120396 0.3048)
			(end 0.120396 0.2794)
			(stroke
				(width 0.1)
				(type default)
			)
			(layer "F.Fab")
		)
		(fp_line
			(start 0.67945 0.3048)
			(end 0.120396 0.3048)
			(stroke
				(width 0.1)
				(type default)
			)
			(layer "F.Fab")
		)
		(fp_line
			(start -0.12065 0.2794)
			(end -0.12065 0.3048)
			(stroke
				(width 0.1)
				(type default)
			)
			(layer "F.Fab")
		)
		(fp_line
			(start 0.120396 0.2794)
			(end -0.12065 0.2794)
			(stroke
				(width 0.1)
				(type default)
			)
			(layer "F.Fab")
		)
		(fp_line
			(start -0.12065 -0.2794)
			(end 0.12065 -0.2794)
			(stroke
				(width 0.1)
				(type default)
			)
			(layer "F.Fab")
		)
		(fp_line
			(start 0.12065 -0.2794)
			(end 0.12065 -0.3048)
			(stroke
				(width 0.1)
				(type default)
			)
			(layer "F.Fab")
		)
		(fp_line
			(start 0.12065 -0.3048)
			(end 0.67945 -0.3048)
			(stroke
				(width 0.1)
				(type default)
			)
			(layer "F.Fab")
		)
		(fp_line
			(start 0.67945 -0.3048)
			(end 0.67945 0.3048)
			(stroke
				(width 0.1)
				(type default)
			)
			(layer "F.Fab")
		)
		(fp_line
			(start -0.67945 -0.305054)
			(end -0.12065 -0.305054)
			(stroke
				(width 0.1)
				(type default)
			)
			(layer "F.Fab")
		)
		(fp_line
			(start -0.12065 -0.305054)
			(end -0.12065 -0.2794)
			(stroke
				(width 0.1)
				(type default)
			)
			(layer "F.Fab")
		)
		(pad "1" smd circle
			(at -0.40005 0 270)
			(size 0 0)
			(layers "F.Cu" "F.Mask" "F.Paste")
			(net "JTAG_P0_R_DBREQ_N")
		)
		(pad "2" smd circle
			(at 0.40005 0 270)
			(size 0 0)
			(layers "F.Cu" "F.Mask" "F.Paste")
			(net "JTAG_CPU0_DBREQ_N")
		)
	)
)
